(kicad_pcb
	(version 20241229)
	(generator "pcbnew")
	(generator_version "9.0")
	(general
		(thickness 1.61)
		(legacy_teardrops no)
	)
	(paper "A3")
	(title_block
		(title "SO-DIMM DDR5 Tester")
		(date "2025-11-26")
		(rev "1.3.0")
		(comment 9 "footprints 77-83 of 627")
	)
	(layers
		(0 "F.Cu" signal)
		(4 "In1.Cu" power)
		(6 "In2.Cu" mixed)
		(8 "In3.Cu" power)
		(10 "In4.Cu" mixed)
		(12 "In5.Cu" power)
		(14 "In6.Cu" mixed)
		(16 "In7.Cu" power)
		(18 "In8.Cu" power)
		(20 "In9.Cu" mixed)
		(22 "In10.Cu" power)
		(2 "B.Cu" signal)
		(9 "F.Adhes" user "F.Adhesive")
		(11 "B.Adhes" user "B.Adhesive")
		(13 "F.Paste" user)
		(15 "B.Paste" user)
		(5 "F.SilkS" user "F.Silkscreen")
		(7 "B.SilkS" user "B.Silkscreen")
		(1 "F.Mask" user)
		(3 "B.Mask" user)
		(17 "Dwgs.User" user "User.Drawings")
		(19 "Cmts.User" user "User.Comments")
		(21 "Eco1.User" user "User.Eco1")
		(23 "Eco2.User" user "User.Eco2")
		(25 "Edge.Cuts" user)
		(27 "Margin" user)
		(31 "F.CrtYd" user "F.Courtyard")
		(29 "B.CrtYd" user "B.Courtyard")
		(35 "F.Fab" user)
		(33 "B.Fab" user)
	)
	(footprint "antmicro-footprints:NetTie-2_SMD_Pad0.127mm"
		(layer "F.Cu")
		(at 189.5 171.701)
		(descr "Net tie, 2 pin, 0.127mm  SMD pads")
		(tags "net tie")
		(property "Reference" "NT5"
			(at -0.128 -1.345 0)
			(layer "F.SilkS")
			(hide yes)
			(effects
				(font
					(size 0.7 0.7)
					(thickness 0.15)
				)
				(justify left bottom)
			)
		)
		(property "Value" "Net-Tie_P0.127mm"
			(at 0 1.199 0)
			(layer "F.Fab")
			(effects
				(font
					(size 0.7 0.7)
					(thickness 0.15)
				)
				(justify left bottom)
			)
		)
		(property "Author" "Antmicro"
			(at 0 0 0)
			(layer "F.Fab")
			(hide yes)
			(effects
				(font
					(size 1 1)
					(thickness 0.15)
				)
			)
		)
		(property "License" "Apache-2.0"
			(at 0 0 0)
			(layer "F.Fab")
			(hide yes)
			(effects
				(font
					(size 1 1)
					(thickness 0.15)
				)
			)
		)
		(property "MPN" ""
			(at 0 0 0)
			(layer "F.Fab")
			(hide yes)
			(effects
				(font
					(size 1 1)
					(thickness 0.15)
				)
			)
		)
		(property "Manufacturer" ""
			(at 0 0 0)
			(layer "F.Fab")
			(hide yes)
			(effects
				(font
					(size 1 1)
					(thickness 0.15)
				)
			)
		)
		(property ki_fp_filters "Net*Tie*")
		(sheetname "/Supply/")
		(sheetfile "supply.kicad_sch")
		(attr smd exclude_from_pos_files exclude_from_bom)
		(net_tie_pad_groups "1, 2")
		(fp_poly
			(pts
				(xy -0.0635 -0.0635) (xy 0.0625 -0.0635) (xy 0.0625 0.0635) (xy -0.0635 0.0635)
			)
			(stroke
				(width 0)
				(type solid)
			)
			(fill yes)
			(layer "F.Cu")
		)
		(pad "1" smd roundrect
			(at -0.127 0 180)
			(size 0.127 0.127)
			(layers "F.Cu")
			(roundrect_rratio 0.5)
			(chamfer_ratio 0)
			(chamfer top_left bottom_left)
			(net 243 "/Supply/3V3_SEN_+")
			(pinfunction "1")
			(pintype "passive")
		)
		(pad "2" smd roundrect
			(at 0.126 0)
			(size 0.127 0.127)
			(layers "F.Cu")
			(roundrect_rratio 0.5)
			(chamfer_ratio 0)
			(chamfer top_left bottom_left)
			(net 52 "/Supply/3V3_local")
			(pinfunction "2")
			(pintype "passive")
		)
	)
	(footprint "antmicro-footprints:C_0603_1608Metric"
		(layer "F.Cu")
		(at 191.168501 165.472 90)
		(descr "Capacitor SMD 0603")
		(tags "capacitor 0603")
		(property "Reference" "C191"
			(at -1.42757 -1.000252 90)
			(layer "F.SilkS")
			(hide yes)
			(effects
				(font
					(size 0.7 0.7)
					(thickness 0.15)
				)
				(justify left bottom)
			)
		)
		(property "Value" "C_22u_0603"
			(at -1.42757 1.770288 90)
			(layer "F.Fab")
			(effects
				(font
					(size 0.7 0.7)
					(thickness 0.15)
				)
				(justify left bottom)
			)
		)
		(property "Datasheet" "https://www.murata.com/products/productdetail?partno=GRM188R60J226MEA0%23"
			(at 0 0 90)
			(layer "F.Fab")
			(hide yes)
			(effects
				(font
					(size 1.27 1.27)
					(thickness 0.15)
				)
			)
		)
		(property "Author" "Antmicro"
			(at 356.640501 -25.696501 0)
			(layer "F.Fab")
			(hide yes)
			(effects
				(font
					(size 1 1)
					(thickness 0.15)
				)
			)
		)
		(property "Dielectric" ""
			(at 356.640501 -25.696501 0)
			(layer "F.Fab")
			(hide yes)
			(effects
				(font
					(size 1 1)
					(thickness 0.15)
				)
			)
		)
		(property "License" "Apache-2.0"
			(at 356.640501 -25.696501 0)
			(layer "F.Fab")
			(hide yes)
			(effects
				(font
					(size 1 1)
					(thickness 0.15)
				)
			)
		)
		(property "MPN" "GRM188R60J226MEA0D"
			(at 356.640501 -25.696501 0)
			(layer "F.Fab")
			(hide yes)
			(effects
				(font
					(size 1 1)
					(thickness 0.15)
				)
			)
		)
		(property "Manufacturer" "Murata"
			(at 356.640501 -25.696501 0)
			(layer "F.Fab")
			(hide yes)
			(effects
				(font
					(size 1 1)
					(thickness 0.15)
				)
			)
		)
		(property "Val" "22u"
			(at 356.640501 -25.696501 0)
			(layer "F.Fab")
			(hide yes)
			(effects
				(font
					(size 1 1)
					(thickness 0.15)
				)
			)
		)
		(property "Voltage" ""
			(at 356.640501 -25.696501 0)
			(layer "F.Fab")
			(hide yes)
			(effects
				(font
					(size 1 1)
					(thickness 0.15)
				)
			)
		)
		(sheetname "/Supply/")
		(sheetfile "supply.kicad_sch")
		(attr smd)
		(fp_line
			(start -0.3 -0.3)
			(end 0.3 -0.3)
			(stroke
				(width 0.15)
				(type solid)
			)
			(layer "F.SilkS")
		)
		(fp_line
			(start -0.3 0.3)
			(end 0.3 0.3)
			(stroke
				(width 0.15)
				(type solid)
			)
			(layer "F.SilkS")
		)
		(fp_rect
			(start -1.24 -0.7)
			(end 1.24 0.7)
			(stroke
				(width 0.05)
				(type solid)
			)
			(fill no)
			(layer "F.CrtYd")
		)
		(fp_rect
			(start -0.8 -0.4)
			(end 0.8 0.4)
			(stroke
				(width 0.15)
				(type solid)
			)
			(fill no)
			(layer "F.Fab")
		)
		(pad "1" smd roundrect
			(at -0.7 0 90)
			(size 0.6 0.8)
			(layers "F.Cu" "F.Mask" "F.Paste")
			(roundrect_rratio 0.2)
			(net 1 "GND")
			(pintype "passive")
		)
		(pad "2" smd roundrect
			(at 0.7 0 90)
			(size 0.6 0.8)
			(layers "F.Cu" "F.Mask" "F.Paste")
			(roundrect_rratio 0.2)
			(net 60 "/Supply/5V_local")
			(pintype "passive")
		)
	)
	(footprint "antmicro-footprints:C_0603_1608Metric"
		(layer "F.Cu")
		(at 168.655501 194.114502 180)
		(descr "Capacitor SMD 0603")
		(tags "capacitor 0603")
		(property "Reference" "C213"
			(at -1.42757 -1.000252 180)
			(layer "F.SilkS")
			(hide yes)
			(effects
				(font
					(size 0.7 0.7)
					(thickness 0.15)
				)
				(justify left bottom)
			)
		)
		(property "Value" "C_22u_0603"
			(at -1.42757 1.770288 180)
			(layer "F.Fab")
			(effects
				(font
					(size 0.7 0.7)
					(thickness 0.15)
				)
				(justify left bottom)
			)
		)
		(property "Datasheet" "https://www.murata.com/products/productdetail?partno=GRM188R60J226MEA0%23"
			(at 0 0 180)
			(layer "F.Fab")
			(hide yes)
			(effects
				(font
					(size 1.27 1.27)
					(thickness 0.15)
				)
			)
		)
		(property "Author" "Antmicro"
			(at 337.311002 388.229004 0)
			(layer "F.Fab")
			(hide yes)
			(effects
				(font
					(size 1 1)
					(thickness 0.15)
				)
			)
		)
		(property "Dielectric" ""
			(at 337.311002 388.229004 0)
			(layer "F.Fab")
			(hide yes)
			(effects
				(font
					(size 1 1)
					(thickness 0.15)
				)
			)
		)
		(property "License" "Apache-2.0"
			(at 337.311002 388.229004 0)
			(layer "F.Fab")
			(hide yes)
			(effects
				(font
					(size 1 1)
					(thickness 0.15)
				)
			)
		)
		(property "MPN" "GRM188R60J226MEA0D"
			(at 337.311002 388.229004 0)
			(layer "F.Fab")
			(hide yes)
			(effects
				(font
					(size 1 1)
					(thickness 0.15)
				)
			)
		)
		(property "Manufacturer" "Murata"
			(at 337.311002 388.229004 0)
			(layer "F.Fab")
			(hide yes)
			(effects
				(font
					(size 1 1)
					(thickness 0.15)
				)
			)
		)
		(property "Val" "22u"
			(at 337.311002 388.229004 0)
			(layer "F.Fab")
			(hide yes)
			(effects
				(font
					(size 1 1)
					(thickness 0.15)
				)
			)
		)
		(property "Voltage" ""
			(at 337.311002 388.229004 0)
			(layer "F.Fab")
			(hide yes)
			(effects
				(font
					(size 1 1)
					(thickness 0.15)
				)
			)
		)
		(sheetname "/Supply/")
		(sheetfile "supply.kicad_sch")
		(attr smd)
		(fp_line
			(start -0.3 0.3)
			(end 0.3 0.3)
			(stroke
				(width 0.15)
				(type solid)
			)
			(layer "F.SilkS")
		)
		(fp_line
			(start -0.3 -0.3)
			(end 0.3 -0.3)
			(stroke
				(width 0.15)
				(type solid)
			)
			(layer "F.SilkS")
		)
		(fp_rect
			(start -1.24 -0.7)
			(end 1.24 0.7)
			(stroke
				(width 0.05)
				(type solid)
			)
			(fill no)
			(layer "F.CrtYd")
		)
		(fp_rect
			(start -0.8 -0.4)
			(end 0.8 0.4)
			(stroke
				(width 0.15)
				(type solid)
			)
			(fill no)
			(layer "F.Fab")
		)
		(pad "1" smd roundrect
			(at -0.7 0 180)
			(size 0.6 0.8)
			(layers "F.Cu" "F.Mask" "F.Paste")
			(roundrect_rratio 0.2)
			(net 1 "GND")
			(pintype "passive")
		)
		(pad "2" smd roundrect
			(at 0.7 0 180)
			(size 0.6 0.8)
			(layers "F.Cu" "F.Mask" "F.Paste")
			(roundrect_rratio 0.2)
			(net 78 "/Supply/1V0_REG")
			(pintype "passive")
		)
	)
	(footprint "antmicro-footprints:R_0402_1005Metric"
		(layer "F.Cu")
		(at 90.748501 126.731921 -90)
		(descr "Resistor SMD 0402")
		(tags "resistor SMD 0402")
		(property "Reference" "R16"
			(at -1.122484 -0.772697 270)
			(layer "F.SilkS")
			(hide yes)
			(effects
				(font
					(size 0.7 0.7)
					(thickness 0.15)
				)
				(justify left bottom)
			)
		)
		(property "Value" "R_4k7_0402"
			(at -1.011843 1.772047 270)
			(layer "F.Fab")
			(effects
				(font
					(size 0.7 0.7)
					(thickness 0.15)
				)
				(justify left bottom)
			)
		)
		(property "Datasheet" "https://www.bourns.com/docs/product-datasheets/cr.pdf"
			(at 0 0 270)
			(layer "F.Fab")
			(hide yes)
			(effects
				(font
					(size 1.27 1.27)
					(thickness 0.15)
				)
			)
		)
		(property "Author" "Antmicro"
			(at -35.98342 217.480422 0)
			(layer "F.Fab")
			(hide yes)
			(effects
				(font
					(size 1 1)
					(thickness 0.15)
				)
			)
		)
		(property "License" "Apache-2.0"
			(at -35.98342 217.480422 0)
			(layer "F.Fab")
			(hide yes)
			(effects
				(font
					(size 1 1)
					(thickness 0.15)
				)
			)
		)
		(property "MPN" "CR0402-FX-4701GLF"
			(at -35.98342 217.480422 0)
			(layer "F.Fab")
			(hide yes)
			(effects
				(font
					(size 1 1)
					(thickness 0.15)
				)
			)
		)
		(property "Manufacturer" "Bourns"
			(at -35.98342 217.480422 0)
			(layer "F.Fab")
			(hide yes)
			(effects
				(font
					(size 1 1)
					(thickness 0.15)
				)
			)
		)
		(property "Tolerance" "1%"
			(at -35.98342 217.480422 0)
			(layer "F.Fab")
			(hide yes)
			(effects
				(font
					(size 1 1)
					(thickness 0.15)
				)
			)
		)
		(property "Val" "4k7"
			(at -35.98342 217.480422 0)
			(layer "F.Fab")
			(hide yes)
			(effects
				(font
					(size 1 1)
					(thickness 0.15)
				)
			)
		)
		(sheetname "/FPGA Config/")
		(sheetfile "fpga-config.kicad_sch")
		(attr smd)
		(fp_rect
			(start -0.93 -0.47)
			(end 0.93 0.47)
			(stroke
				(width 0.05)
				(type solid)
			)
			(fill no)
			(layer "F.CrtYd")
		)
		(fp_rect
			(start -0.5 -0.25)
			(end 0.5 0.25)
			(stroke
				(width 0.15)
				(type solid)
			)
			(fill no)
			(layer "F.Fab")
		)
		(pad "1" smd roundrect
			(at -0.485 0 270)
			(size 0.59 0.64)
			(layers "F.Cu" "F.Mask" "F.Paste")
			(roundrect_rratio 0.25)
			(net 200 "+3V3")
			(pintype "passive")
		)
		(pad "2" smd roundrect
			(at 0.485 0 270)
			(size 0.59 0.64)
			(layers "F.Cu" "F.Mask" "F.Paste")
			(roundrect_rratio 0.25)
			(net 614 "/FPGA Config/INIT_B")
			(pintype "passive")
		)
	)
	(footprint "antmicro-footprints:C_0402_1005Metric"
		(layer "F.Cu")
		(at 183.115 128.2)
		(descr "Capacitor SMD 0402")
		(tags "capacitor SMD 0402")
		(property "Reference" "C127"
			(at 0 -0.699 0)
			(layer "F.SilkS")
			(hide yes)
			(effects
				(font
					(size 0.7 0.7)
					(thickness 0.15)
				)
				(justify left bottom)
			)
		)
		(property "Value" "C_1u_0402"
			(at -1.022927 2.155213 0)
			(layer "F.Fab")
			(effects
				(font
					(size 0.7 0.7)
					(thickness 0.15)
				)
				(justify left bottom)
			)
		)
		(property "Datasheet" "https://product.tdk.com/en/search/capacitor/ceramic/mlcc/info?part_no=C1005X6S1A105K050BC"
			(at 0 0 0)
			(layer "F.Fab")
			(hide yes)
			(effects
				(font
					(size 1.27 1.27)
					(thickness 0.15)
				)
			)
		)
		(property "Author" "Antmicro"
			(at 0 0 0)
			(layer "F.Fab")
			(hide yes)
			(effects
				(font
					(size 1 1)
					(thickness 0.15)
				)
			)
		)
		(property "Dielectric" ""
			(at 0 0 0)
			(layer "F.Fab")
			(hide yes)
			(effects
				(font
					(size 1 1)
					(thickness 0.15)
				)
			)
		)
		(property "License" "Apache-2.0"
			(at 0 0 0)
			(layer "F.Fab")
			(hide yes)
			(effects
				(font
					(size 1 1)
					(thickness 0.15)
				)
			)
		)
		(property "MPN" "C1005X6S1A105K050BC"
			(at 0 0 0)
			(layer "F.Fab")
			(hide yes)
			(effects
				(font
					(size 1 1)
					(thickness 0.15)
				)
			)
		)
		(property "Manufacturer" "TDK"
			(at 0 0 0)
			(layer "F.Fab")
			(hide yes)
			(effects
				(font
					(size 1 1)
					(thickness 0.15)
				)
			)
		)
		(property "Val" "1u"
			(at 0 0 0)
			(layer "F.Fab")
			(hide yes)
			(effects
				(font
					(size 1 1)
					(thickness 0.15)
				)
			)
		)
		(property "Voltage" ""
			(at 0 0 0)
			(layer "F.Fab")
			(hide yes)
			(effects
				(font
					(size 1 1)
					(thickness 0.15)
				)
			)
		)
		(sheetname "/DDR5 SODIMM/")
		(sheetfile "ddr5-sodimm.kicad_sch")
		(attr exclude_from_pos_files exclude_from_bom dnp)
		(fp_rect
			(start -0.9659 -0.481258)
			(end 0.9649 0.458742)
			(stroke
				(width 0.05)
				(type solid)
			)
			(fill no)
			(layer "F.CrtYd")
		)
		(fp_line
			(start -0.499 -0.25)
			(end 0.499 -0.25)
			(stroke
				(width 0.15)
				(type solid)
			)
			(layer "F.Fab")
		)
		(fp_line
			(start -0.499 0.248)
			(end -0.499 -0.25)
			(stroke
				(width 0.15)
				(type solid)
			)
			(layer "F.Fab")
		)
		(fp_line
			(start 0.499 -0.25)
			(end 0.499 0.248)
			(stroke
				(width 0.15)
				(type solid)
			)
			(layer "F.Fab")
		)
		(fp_line
			(start 0.499 0.248)
			(end -0.499 0.248)
			(stroke
				(width 0.15)
				(type solid)
			)
			(layer "F.Fab")
		)
		(pad "1" smd roundrect
			(at -0.484 0)
			(size 0.59 0.64)
			(layers "F.Cu" "F.Mask" "F.Paste")
			(roundrect_rratio 0.25)
			(net 106 "HOT_SWAP_BUTTON")
			(pintype "passive")
		)
		(pad "2" smd roundrect
			(at 0.484 0)
			(size 0.59 0.64)
			(layers "F.Cu" "F.Mask" "F.Paste")
			(roundrect_rratio 0.25)
			(net 1 "GND")
			(pintype "passive")
		)
	)
	(footprint "antmicro-footprints:F_1206_3216Metric"
		(layer "F.Cu")
		(at 188.15 128.6 -90)
		(property "Reference" "F1"
			(at -0.6 -2.25 270)
			(layer "F.SilkS")
			(effects
				(font
					(size 0.7 0.7)
					(thickness 0.15)
				)
				(justify left bottom)
			)
		)
		(property "Value" "F_4A_1206"
			(at 0 2 270)
			(layer "F.Fab")
			(effects
				(font
					(size 0.7 0.7)
					(thickness 0.15)
				)
				(justify left bottom)
			)
		)
		(property "Datasheet" "https://www.littelfuse.com/media?resourcetype=datasheets&itemid=dbe9bcd7-6072-4adf-bf5b-d33e52a6b90f&filename=littelfuse-fuse-466-datasheet"
			(at 0 0 270)
			(layer "F.Fab")
			(hide yes)
			(effects
				(font
					(size 1.27 1.27)
					(thickness 0.15)
				)
			)
		)
		(property "Author" "Antmicro"
			(at 59.55 316.75 0)
			(layer "F.Fab")
			(hide yes)
			(effects
				(font
					(size 1 1)
					(thickness 0.15)
				)
			)
		)
		(property "License" "Apache-2.0"
			(at 59.55 316.75 0)
			(layer "F.Fab")
			(hide yes)
			(effects
				(font
					(size 1 1)
					(thickness 0.15)
				)
			)
		)
		(property "MPN" "0466004.NR "
			(at 59.55 316.75 0)
			(layer "F.Fab")
			(hide yes)
			(effects
				(font
					(size 1 1)
					(thickness 0.15)
				)
			)
		)
		(property "Manufacturer" "Littelfuse"
			(at 59.55 316.75 0)
			(layer "F.Fab")
			(hide yes)
			(effects
				(font
					(size 1 1)
					(thickness 0.15)
				)
			)
		)
		(sheetname "/Supply/")
		(sheetfile "supply.kicad_sch")
		(attr smd)
		(fp_line
			(start -0.413 0.792)
			(end 0.36 0.792)
			(stroke
				(width 0.15)
				(type solid)
			)
			(layer "F.SilkS")
		)
		(fp_line
			(start -0.413 -0.861)
			(end 0.36 -0.861)
			(stroke
				(width 0.15)
				(type solid)
			)
			(layer "F.SilkS")
		)
		(fp_rect
			(start -1.95 -1)
			(end 1.95 1)
			(stroke
				(width 0.05)
				(type solid)
			)
			(fill no)
			(layer "F.CrtYd")
		)
		(fp_line
			(start -1.677 0.792)
			(end -1.677 -0.861)
			(stroke
				(width 0.15)
				(type solid)
			)
			(layer "F.Fab")
		)
		(fp_line
			(start 1.624 0.792)
			(end -1.677 0.792)
			(stroke
				(width 0.15)
				(type solid)
			)
			(layer "F.Fab")
		)
		(fp_line
			(start -1.677 -0.861)
			(end 1.624 -0.861)
			(stroke
				(width 0.15)
				(type solid)
			)
			(layer "F.Fab")
		)
		(fp_line
			(start 1.624 -0.861)
			(end 1.624 0.792)
			(stroke
				(width 0.15)
				(type solid)
			)
			(layer "F.Fab")
		)
		(pad "1" smd rect
			(at -1.35 0 270)
			(size 1.143 2.032)
			(layers "F.Cu" "F.Mask" "F.Paste")
			(net 597 "/Supply/12V_aux")
			(pintype "passive")
		)
		(pad "2" smd rect
			(at 1.35 0 270)
			(size 1.143 2.032)
			(layers "F.Cu" "F.Mask" "F.Paste")
			(net 595 "/Supply/12V_aux_fused")
			(pintype "passive")
		)
	)
	(footprint "antmicro-footprints:C_0402_1005Metric"
		(layer "F.Cu")
		(at 184.991759 130.907099)
		(descr "Capacitor SMD 0402")
		(tags "capacitor SMD 0402")
		(property "Reference" "C175"
			(at 0 -0.699 0)
			(layer "F.SilkS")
			(hide yes)
			(effects
				(font
					(size 0.7 0.7)
					(thickness 0.15)
				)
				(justify left bottom)
			)
		)
		(property "Value" "C_100n_0402"
			(at -1.022927 2.155213 0)
			(layer "F.Fab")
			(effects
				(font
					(size 0.7 0.7)
					(thickness 0.15)
				)
				(justify left bottom)
			)
		)
		(property "Datasheet" "https://www.murata.com/products/productdetail?partno=GRM155R61H104KE14%23"
			(at 0 0 0)
			(layer "F.Fab")
			(hide yes)
			(effects
				(font
					(size 1.27 1.27)
					(thickness 0.15)
				)
			)
		)
		(property "Author" "Antmicro"
			(at 0 0 0)
			(layer "F.Fab")
			(hide yes)
			(effects
				(font
					(size 1 1)
					(thickness 0.15)
				)
			)
		)
		(property "Dielectric" "X5R"
			(at 0 0 0)
			(layer "F.Fab")
			(hide yes)
			(effects
				(font
					(size 1 1)
					(thickness 0.15)
				)
			)
		)
		(property "License" "Apache-2.0"
			(at 0 0 0)
			(layer "F.Fab")
			(hide yes)
			(effects
				(font
					(size 1 1)
					(thickness 0.15)
				)
			)
		)
		(property "MPN" "GRM155R61H104KE14D"
			(at 0 0 0)
			(layer "F.Fab")
			(hide yes)
			(effects
				(font
					(size 1 1)
					(thickness 0.15)
				)
			)
		)
		(property "Manufacturer" "Murata"
			(at 0 0 0)
			(layer "F.Fab")
			(hide yes)
			(effects
				(font
					(size 1 1)
					(thickness 0.15)
				)
			)
		)
		(property "Val" "100n"
			(at 0 0 0)
			(layer "F.Fab")
			(hide yes)
			(effects
				(font
					(size 1 1)
					(thickness 0.15)
				)
			)
		)
		(property "Voltage" "50V"
			(at 0 0 0)
			(layer "F.Fab")
			(hide yes)
			(effects
				(font
					(size 1 1)
					(thickness 0.15)
				)
			)
		)
		(sheetname "/Supply/")
		(sheetfile "supply.kicad_sch")
		(attr smd)
		(fp_rect
			(start -0.9659 -0.481258)
			(end 0.9649 0.458742)
			(stroke
				(width 0.05)
				(type solid)
			)
			(fill no)
			(layer "F.CrtYd")
		)
		(fp_line
			(start -0.499 -0.25)
			(end 0.499 -0.25)
			(stroke
				(width 0.15)
				(type solid)
			)
			(layer "F.Fab")
		)
		(fp_line
			(start -0.499 0.248)
			(end -0.499 -0.25)
			(stroke
				(width 0.15)
				(type solid)
			)
			(layer "F.Fab")
		)
		(fp_line
			(start 0.499 -0.25)
			(end 0.499 0.248)
			(stroke
				(width 0.15)
				(type solid)
			)
			(layer "F.Fab")
		)
		(fp_line
			(start 0.499 0.248)
			(end -0.499 0.248)
			(stroke
				(width 0.15)
				(type solid)
			)
			(layer "F.Fab")
		)
		(pad "1" smd roundrect
			(at -0.484 0)
			(size 0.59 0.64)
			(layers "F.Cu" "F.Mask" "F.Paste")
			(roundrect_rratio 0.25)
			(net 1 "GND")
			(pintype "passive")
		)
		(pad "2" smd roundrect
			(at 0.484 0)
			(size 0.59 0.64)
			(layers "F.Cu" "F.Mask" "F.Paste")
			(roundrect_rratio 0.25)
			(net 595 "/Supply/12V_aux_fused")
			(pintype "passive")
		)
	)
)
